(kicad_pcb
	(version 20260206)
	(generator "pcbnew")
	(generator_version "10.0")
	(general
		(thickness 1.6)
		(legacy_teardrops no)
	)
	(paper "A4")
	(title_block
		(title "12092022_DA0F0TMDCD0_F0T_Management_Board_D_brd_V3_OCP.brd")
		(comment 1 "Grand Teton / footprints 745-750 of 1440")
	)
	(layers
		(0 "F.Cu" signal "TOP")
		(4 "In1.Cu" signal "GND")
		(6 "In2.Cu" signal "IN1")
		(8 "In3.Cu" signal "GND1")
		(10 "In4.Cu" signal "IN2")
		(12 "In5.Cu" signal "VCC")
		(14 "In6.Cu" signal "VCC1")
		(16 "In7.Cu" signal "IN3")
		(18 "In8.Cu" signal "GND2")
		(20 "In9.Cu" signal "IN4")
		(22 "In10.Cu" signal "GND3")
		(2 "B.Cu" signal "BOTTOM")
		(9 "F.Adhes" user "F.Adhesive")
		(11 "B.Adhes" user "B.Adhesive")
		(13 "F.Paste" user "Package Geometry/Pastemask Top")
		(15 "B.Paste" user "Package Geometry/Pastemask Bottom")
		(5 "F.SilkS" user "Ref Des/Silkscreen Top")
		(7 "B.SilkS" user "Ref Des/Silkscreen Bottom")
		(1 "F.Mask" user "Board Geometry/Soldermask Top")
		(3 "B.Mask" user "Board Geometry/Soldermask Bottom")
		(17 "Dwgs.User" user "User.Drawings")
		(19 "Cmts.User" user "User.Comments")
		(21 "Eco1.User" user "User.Eco1")
		(23 "Eco2.User" user "User.Eco2")
		(25 "Edge.Cuts" user "Board Geometry/Outline")
		(27 "Margin" user)
		(31 "F.CrtYd" user "Package Geometry/Place Bound Top")
		(29 "B.CrtYd" user "Package Geometry/Place Bound Bottom")
		(35 "F.Fab" user "Ref Des/Assembly Top")
		(33 "B.Fab" user "Ref Des/Assembly Bottom")
	)
	(footprint ""
		(layer "B.Cu")
		(at 79.756 -33.4645 -90)
		(property "Reference" "R35"
			(at 0 0 90)
			(layer "B.SilkS")
			(hide yes)
			(effects
				(font
					(size 1.27 1.27)
				)
				(justify mirror)
			)
		)
		(property "Value" ""
			(at 0 0 90)
			(layer "B.Fab")
			(effects
				(font
					(size 1.27 1.27)
				)
				(justify mirror)
			)
		)
		(duplicate_pad_numbers_are_jumpers no)
		(fp_line
			(start -0.7874 0.4064)
			(end 0.7874 0.4064)
			(stroke
				(width 0.1524)
				(type default)
			)
			(layer "B.SilkS")
		)
		(fp_line
			(start 0.7874 0.4064)
			(end 0.7874 -0.4064)
			(stroke
				(width 0.1524)
				(type default)
			)
			(layer "B.SilkS")
		)
		(fp_line
			(start -0.7874 -0.4064)
			(end -0.7874 0.4064)
			(stroke
				(width 0.1524)
				(type default)
			)
			(layer "B.SilkS")
		)
		(fp_line
			(start 0.7874 -0.4064)
			(end -0.7874 -0.4064)
			(stroke
				(width 0.1524)
				(type default)
			)
			(layer "B.SilkS")
		)
		(fp_line
			(start -0.67945 0.3048)
			(end -0.120396 0.3048)
			(stroke
				(width 0.1)
				(type default)
			)
			(layer "B.Fab")
		)
		(fp_line
			(start -0.120396 0.3048)
			(end -0.120396 0.2794)
			(stroke
				(width 0.1)
				(type default)
			)
			(layer "B.Fab")
		)
		(fp_line
			(start 0.12065 0.3048)
			(end 0.67945 0.3048)
			(stroke
				(width 0.1)
				(type default)
			)
			(layer "B.Fab")
		)
		(fp_line
			(start 0.67945 0.3048)
			(end 0.67945 -0.305054)
			(stroke
				(width 0.1)
				(type default)
			)
			(layer "B.Fab")
		)
		(fp_line
			(start -0.120396 0.2794)
			(end 0.12065 0.2794)
			(stroke
				(width 0.1)
				(type default)
			)
			(layer "B.Fab")
		)
		(fp_line
			(start 0.12065 0.2794)
			(end 0.12065 0.3048)
			(stroke
				(width 0.1)
				(type default)
			)
			(layer "B.Fab")
		)
		(fp_line
			(start -0.12065 -0.2794)
			(end -0.12065 -0.3048)
			(stroke
				(width 0.1)
				(type default)
			)
			(layer "B.Fab")
		)
		(fp_line
			(start 0.12065 -0.2794)
			(end -0.12065 -0.2794)
			(stroke
				(width 0.1)
				(type default)
			)
			(layer "B.Fab")
		)
		(fp_line
			(start -0.67945 -0.3048)
			(end -0.67945 0.3048)
			(stroke
				(width 0.1)
				(type default)
			)
			(layer "B.Fab")
		)
		(fp_line
			(start -0.12065 -0.3048)
			(end -0.67945 -0.3048)
			(stroke
				(width 0.1)
				(type default)
			)
			(layer "B.Fab")
		)
		(fp_line
			(start 0.12065 -0.305054)
			(end 0.12065 -0.2794)
			(stroke
				(width 0.1)
				(type default)
			)
			(layer "B.Fab")
		)
		(fp_line
			(start 0.67945 -0.305054)
			(end 0.12065 -0.305054)
			(stroke
				(width 0.1)
				(type default)
			)
			(layer "B.Fab")
		)
		(pad "1" smd circle
			(at 0.40005 0 90)
			(size 0 0)
			(layers "B.Cu" "B.Mask" "B.Paste")
			(net "PWRGD_P2V5_AUX")
		)
		(pad "2" smd circle
			(at -0.40005 0 90)
			(size 0 0)
			(layers "B.Cu" "B.Mask" "B.Paste")
			(net "PWRGD_P2V5_AUX_R")
		)
	)
	(footprint ""
		(layer "B.Cu")
		(at 81.129886 -39.974012)
		(property "Reference" "R345"
			(at 0 0 0)
			(layer "B.SilkS")
			(hide yes)
			(effects
				(font
					(size 1.27 1.27)
				)
				(justify mirror)
			)
		)
		(property "Value" ""
			(at 0 0 0)
			(layer "B.Fab")
			(effects
				(font
					(size 1.27 1.27)
				)
				(justify mirror)
			)
		)
		(duplicate_pad_numbers_are_jumpers no)
		(fp_line
			(start -0.7874 -0.4064)
			(end -0.7874 0.4064)
			(stroke
				(width 0.1524)
				(type default)
			)
			(layer "B.SilkS")
		)
		(fp_line
			(start -0.7874 0.4064)
			(end 0.7874 0.4064)
			(stroke
				(width 0.1524)
				(type default)
			)
			(layer "B.SilkS")
		)
		(fp_line
			(start 0.7874 -0.4064)
			(end -0.7874 -0.4064)
			(stroke
				(width 0.1524)
				(type default)
			)
			(layer "B.SilkS")
		)
		(fp_line
			(start 0.7874 0.4064)
			(end 0.7874 -0.4064)
			(stroke
				(width 0.1524)
				(type default)
			)
			(layer "B.SilkS")
		)
		(fp_line
			(start -0.67945 -0.3048)
			(end -0.67945 0.3048)
			(stroke
				(width 0.1)
				(type default)
			)
			(layer "B.Fab")
		)
		(fp_line
			(start -0.67945 0.3048)
			(end -0.120396 0.3048)
			(stroke
				(width 0.1)
				(type default)
			)
			(layer "B.Fab")
		)
		(fp_line
			(start -0.12065 -0.3048)
			(end -0.67945 -0.3048)
			(stroke
				(width 0.1)
				(type default)
			)
			(layer "B.Fab")
		)
		(fp_line
			(start -0.12065 -0.2794)
			(end -0.12065 -0.3048)
			(stroke
				(width 0.1)
				(type default)
			)
			(layer "B.Fab")
		)
		(fp_line
			(start -0.120396 0.2794)
			(end 0.12065 0.2794)
			(stroke
				(width 0.1)
				(type default)
			)
			(layer "B.Fab")
		)
		(fp_line
			(start -0.120396 0.3048)
			(end -0.120396 0.2794)
			(stroke
				(width 0.1)
				(type default)
			)
			(layer "B.Fab")
		)
		(fp_line
			(start 0.12065 -0.305054)
			(end 0.12065 -0.2794)
			(stroke
				(width 0.1)
				(type default)
			)
			(layer "B.Fab")
		)
		(fp_line
			(start 0.12065 -0.2794)
			(end -0.12065 -0.2794)
			(stroke
				(width 0.1)
				(type default)
			)
			(layer "B.Fab")
		)
		(fp_line
			(start 0.12065 0.2794)
			(end 0.12065 0.3048)
			(stroke
				(width 0.1)
				(type default)
			)
			(layer "B.Fab")
		)
		(fp_line
			(start 0.12065 0.3048)
			(end 0.67945 0.3048)
			(stroke
				(width 0.1)
				(type default)
			)
			(layer "B.Fab")
		)
		(fp_line
			(start 0.67945 -0.305054)
			(end 0.12065 -0.305054)
			(stroke
				(width 0.1)
				(type default)
			)
			(layer "B.Fab")
		)
		(fp_line
			(start 0.67945 0.3048)
			(end 0.67945 -0.305054)
			(stroke
				(width 0.1)
				(type default)
			)
			(layer "B.Fab")
		)
		(pad "1" smd circle
			(at 0.40005 0 180)
			(size 0 0)
			(layers "B.Cu" "B.Mask" "B.Paste")
			(net "GND")
		)
		(pad "2" smd circle
			(at -0.40005 0 180)
			(size 0 0)
			(layers "B.Cu" "B.Mask" "B.Paste")
			(net "M_BMC_DDR4_MBG0")
		)
	)
	(footprint ""
		(layer "B.Cu")
		(at 21.3106 -90.8558 90)
		(property "Reference" "C189"
			(at 0 0 90)
			(layer "B.SilkS")
			(hide yes)
			(effects
				(font
					(size 1.27 1.27)
				)
				(justify mirror)
			)
		)
		(property "Value" ""
			(at 0 0 90)
			(layer "B.Fab")
			(effects
				(font
					(size 1.27 1.27)
				)
				(justify mirror)
			)
		)
		(duplicate_pad_numbers_are_jumpers no)
		(fp_line
			(start 0.69215 -0.2921)
			(end -0.69215 -0.2921)
			(stroke
				(width 0.1524)
				(type default)
			)
			(layer "B.SilkS")
		)
		(fp_line
			(start -0.69215 -0.2921)
			(end -0.69215 0.2921)
			(stroke
				(width 0.1524)
				(type default)
			)
			(layer "B.SilkS")
		)
		(fp_line
			(start 0.69215 0.2921)
			(end 0.69215 -0.2921)
			(stroke
				(width 0.1524)
				(type default)
			)
			(layer "B.SilkS")
		)
		(fp_line
			(start -0.69215 0.2921)
			(end 0.69215 0.2921)
			(stroke
				(width 0.1524)
				(type default)
			)
			(layer "B.SilkS")
		)
		(fp_line
			(start 0.51435 -0.2794)
			(end -0.51435 -0.2794)
			(stroke
				(width 0.1)
				(type default)
			)
			(layer "B.Fab")
		)
		(fp_line
			(start -0.51435 -0.2794)
			(end -0.51435 0.2794)
			(stroke
				(width 0.1)
				(type default)
			)
			(layer "B.Fab")
		)
		(fp_line
			(start 0.51435 0.2794)
			(end 0.51435 -0.2794)
			(stroke
				(width 0.1)
				(type default)
			)
			(layer "B.Fab")
		)
		(fp_line
			(start -0.51435 0.2794)
			(end 0.51435 0.2794)
			(stroke
				(width 0.1)
				(type default)
			)
			(layer "B.Fab")
		)
		(pad "1" smd circle
			(at 0.40005 0 270)
			(size 0 0)
			(layers "B.Cu" "B.Mask" "B.Paste")
			(net "VCCIO0")
		)
		(pad "2" smd circle
			(at -0.40005 0 270)
			(size 0 0)
			(layers "B.Cu" "B.Mask" "B.Paste")
			(net "GND")
		)
		(zone
			(layer "B.Cu")
			(hatch none 0.5)
			(connect_pads
				(clearance 0)
			)
			(min_thickness 0.25)
			(keepout
				(tracks not_allowed)
				(vias allowed)
				(pads allowed)
				(copperpour not_allowed)
				(footprints allowed)
			)
			(placement
				(enabled no)
				(sheetname "")
			)
			(fill
				(thermal_gap 0.5)
				(thermal_bridge_width 0.5)
				(island_removal_mode 0)
			)
			(polygon
				(pts
					(xy 21.39823 -91.0463) (xy 21.456396 -90.95486) (xy 21.456396 -90.75547) (xy 21.39823 -90.6653)
					(xy 21.22297 -90.6653) (xy 21.16455 -90.75547) (xy 21.16455 -90.95486) (xy 21.222716 -91.0463)
				)
			)
		)
	)
	(footprint ""
		(layer "B.Cu")
		(at 66.3956 -106.4387 -90)
		(property "Reference" "R46"
			(at 0 0 90)
			(layer "B.SilkS")
			(hide yes)
			(effects
				(font
					(size 1.27 1.27)
				)
				(justify mirror)
			)
		)
		(property "Value" ""
			(at 0 0 90)
			(layer "B.Fab")
			(effects
				(font
					(size 1.27 1.27)
				)
				(justify mirror)
			)
		)
		(duplicate_pad_numbers_are_jumpers no)
		(fp_line
			(start -0.7874 0.4064)
			(end 0.7874 0.4064)
			(stroke
				(width 0.1524)
				(type default)
			)
			(layer "B.SilkS")
		)
		(fp_line
			(start 0.7874 0.4064)
			(end 0.7874 -0.4064)
			(stroke
				(width 0.1524)
				(type default)
			)
			(layer "B.SilkS")
		)
		(fp_line
			(start -0.7874 -0.4064)
			(end -0.7874 0.4064)
			(stroke
				(width 0.1524)
				(type default)
			)
			(layer "B.SilkS")
		)
		(fp_line
			(start 0.7874 -0.4064)
			(end -0.7874 -0.4064)
			(stroke
				(width 0.1524)
				(type default)
			)
			(layer "B.SilkS")
		)
		(fp_line
			(start -0.67945 0.3048)
			(end -0.120396 0.3048)
			(stroke
				(width 0.1)
				(type default)
			)
			(layer "B.Fab")
		)
		(fp_line
			(start -0.120396 0.3048)
			(end -0.120396 0.2794)
			(stroke
				(width 0.1)
				(type default)
			)
			(layer "B.Fab")
		)
		(fp_line
			(start 0.12065 0.3048)
			(end 0.67945 0.3048)
			(stroke
				(width 0.1)
				(type default)
			)
			(layer "B.Fab")
		)
		(fp_line
			(start 0.67945 0.3048)
			(end 0.67945 -0.305054)
			(stroke
				(width 0.1)
				(type default)
			)
			(layer "B.Fab")
		)
		(fp_line
			(start -0.120396 0.2794)
			(end 0.12065 0.2794)
			(stroke
				(width 0.1)
				(type default)
			)
			(layer "B.Fab")
		)
		(fp_line
			(start 0.12065 0.2794)
			(end 0.12065 0.3048)
			(stroke
				(width 0.1)
				(type default)
			)
			(layer "B.Fab")
		)
		(fp_line
			(start -0.12065 -0.2794)
			(end -0.12065 -0.3048)
			(stroke
				(width 0.1)
				(type default)
			)
			(layer "B.Fab")
		)
		(fp_line
			(start 0.12065 -0.2794)
			(end -0.12065 -0.2794)
			(stroke
				(width 0.1)
				(type default)
			)
			(layer "B.Fab")
		)
		(fp_line
			(start -0.67945 -0.3048)
			(end -0.67945 0.3048)
			(stroke
				(width 0.1)
				(type default)
			)
			(layer "B.Fab")
		)
		(fp_line
			(start -0.12065 -0.3048)
			(end -0.67945 -0.3048)
			(stroke
				(width 0.1)
				(type default)
			)
			(layer "B.Fab")
		)
		(fp_line
			(start 0.12065 -0.305054)
			(end 0.12065 -0.2794)
			(stroke
				(width 0.1)
				(type default)
			)
			(layer "B.Fab")
		)
		(fp_line
			(start 0.67945 -0.305054)
			(end 0.12065 -0.305054)
			(stroke
				(width 0.1)
				(type default)
			)
			(layer "B.Fab")
		)
		(pad "1" smd circle
			(at 0.40005 0 90)
			(size 0 0)
			(layers "B.Cu" "B.Mask" "B.Paste")
			(net "SMB_BMC_MM14_SDA")
		)
		(pad "2" smd circle
			(at -0.40005 0 90)
			(size 0 0)
			(layers "B.Cu" "B.Mask" "B.Paste")
			(net "SMB_BMC_MM14_R1_SDA")
		)
	)
	(footprint ""
		(layer "B.Cu")
		(at 54.853332 -50.652934 -90)
		(property "Reference" "C111"
			(at 0 0 90)
			(layer "B.SilkS")
			(hide yes)
			(effects
				(font
					(size 1.27 1.27)
				)
				(justify mirror)
			)
		)
		(property "Value" ""
			(at 0 0 90)
			(layer "B.Fab")
			(effects
				(font
					(size 1.27 1.27)
				)
				(justify mirror)
			)
		)
		(duplicate_pad_numbers_are_jumpers no)
		(fp_line
			(start -0.7874 0.4064)
			(end 0.7874 0.4064)
			(stroke
				(width 0.1524)
				(type default)
			)
			(layer "B.SilkS")
		)
		(fp_line
			(start 0.7874 0.4064)
			(end 0.7874 -0.4064)
			(stroke
				(width 0.1524)
				(type default)
			)
			(layer "B.SilkS")
		)
		(fp_line
			(start -0.7874 -0.4064)
			(end -0.7874 0.4064)
			(stroke
				(width 0.1524)
				(type default)
			)
			(layer "B.SilkS")
		)
		(fp_line
			(start 0.7874 -0.4064)
			(end -0.7874 -0.4064)
			(stroke
				(width 0.1524)
				(type default)
			)
			(layer "B.SilkS")
		)
		(fp_line
			(start -0.67945 0.3048)
			(end -0.120396 0.3048)
			(stroke
				(width 0.1)
				(type default)
			)
			(layer "B.Fab")
		)
		(fp_line
			(start -0.120396 0.3048)
			(end -0.120396 0.2794)
			(stroke
				(width 0.1)
				(type default)
			)
			(layer "B.Fab")
		)
		(fp_line
			(start 0.12065 0.3048)
			(end 0.67945 0.3048)
			(stroke
				(width 0.1)
				(type default)
			)
			(layer "B.Fab")
		)
		(fp_line
			(start 0.67945 0.3048)
			(end 0.67945 -0.305054)
			(stroke
				(width 0.1)
				(type default)
			)
			(layer "B.Fab")
		)
		(fp_line
			(start -0.120396 0.2794)
			(end 0.12065 0.2794)
			(stroke
				(width 0.1)
				(type default)
			)
			(layer "B.Fab")
		)
		(fp_line
			(start 0.12065 0.2794)
			(end 0.12065 0.3048)
			(stroke
				(width 0.1)
				(type default)
			)
			(layer "B.Fab")
		)
		(fp_line
			(start -0.12065 -0.2794)
			(end -0.12065 -0.3048)
			(stroke
				(width 0.1)
				(type default)
			)
			(layer "B.Fab")
		)
		(fp_line
			(start 0.12065 -0.2794)
			(end -0.12065 -0.2794)
			(stroke
				(width 0.1)
				(type default)
			)
			(layer "B.Fab")
		)
		(fp_line
			(start -0.67945 -0.3048)
			(end -0.67945 0.3048)
			(stroke
				(width 0.1)
				(type default)
			)
			(layer "B.Fab")
		)
		(fp_line
			(start -0.12065 -0.3048)
			(end -0.67945 -0.3048)
			(stroke
				(width 0.1)
				(type default)
			)
			(layer "B.Fab")
		)
		(fp_line
			(start 0.12065 -0.305054)
			(end 0.12065 -0.2794)
			(stroke
				(width 0.1)
				(type default)
			)
			(layer "B.Fab")
		)
		(fp_line
			(start 0.67945 -0.305054)
			(end 0.12065 -0.305054)
			(stroke
				(width 0.1)
				(type default)
			)
			(layer "B.Fab")
		)
		(pad "1" smd circle
			(at 0.40005 0 90)
			(size 0 0)
			(layers "B.Cu" "B.Mask" "B.Paste")
			(net "P1V8_AUX")
		)
		(pad "2" smd circle
			(at -0.40005 0 90)
			(size 0 0)
			(layers "B.Cu" "B.Mask" "B.Paste")
			(net "GND")
		)
	)
	(footprint ""
		(layer "B.Cu")
		(at 81.129886 -43.022012 180)
		(property "Reference" "C8"
			(at 0 0 0)
			(layer "B.SilkS")
			(hide yes)
			(effects
				(font
					(size 1.27 1.27)
				)
				(justify mirror)
			)
		)
		(property "Value" ""
			(at 0 0 0)
			(layer "B.Fab")
			(effects
				(font
					(size 1.27 1.27)
				)
				(justify mirror)
			)
		)
		(duplicate_pad_numbers_are_jumpers no)
		(fp_line
			(start 0.7874 0.4064)
			(end 0.7874 -0.4064)
			(stroke
				(width 0.1524)
				(type default)
			)
			(layer "B.SilkS")
		)
		(fp_line
			(start 0.7874 -0.4064)
			(end -0.7874 -0.4064)
			(stroke
				(width 0.1524)
				(type default)
			)
			(layer "B.SilkS")
		)
		(fp_line
			(start -0.7874 0.4064)
			(end 0.7874 0.4064)
			(stroke
				(width 0.1524)
				(type default)
			)
			(layer "B.SilkS")
		)
		(fp_line
			(start -0.7874 -0.4064)
			(end -0.7874 0.4064)
			(stroke
				(width 0.1524)
				(type default)
			)
			(layer "B.SilkS")
		)
		(fp_line
			(start 0.67945 0.3048)
			(end 0.67945 -0.305054)
			(stroke
				(width 0.1)
				(type default)
			)
			(layer "B.Fab")
		)
		(fp_line
			(start 0.67945 -0.305054)
			(end 0.12065 -0.305054)
			(stroke
				(width 0.1)
				(type default)
			)
			(layer "B.Fab")
		)
		(fp_line
			(start 0.12065 0.3048)
			(end 0.67945 0.3048)
			(stroke
				(width 0.1)
				(type default)
			)
			(layer "B.Fab")
		)
		(fp_line
			(start 0.12065 0.2794)
			(end 0.12065 0.3048)
			(stroke
				(width 0.1)
				(type default)
			)
			(layer "B.Fab")
		)
		(fp_line
			(start 0.12065 -0.2794)
			(end -0.12065 -0.2794)
			(stroke
				(width 0.1)
				(type default)
			)
			(layer "B.Fab")
		)
		(fp_line
			(start 0.12065 -0.305054)
			(end 0.12065 -0.2794)
			(stroke
				(width 0.1)
				(type default)
			)
			(layer "B.Fab")
		)
		(fp_line
			(start -0.120396 0.3048)
			(end -0.120396 0.2794)
			(stroke
				(width 0.1)
				(type default)
			)
			(layer "B.Fab")
		)
		(fp_line
			(start -0.120396 0.2794)
			(end 0.12065 0.2794)
			(stroke
				(width 0.1)
				(type default)
			)
			(layer "B.Fab")
		)
		(fp_line
			(start -0.12065 -0.2794)
			(end -0.12065 -0.3048)
			(stroke
				(width 0.1)
				(type default)
			)
			(layer "B.Fab")
		)
		(fp_line
			(start -0.12065 -0.3048)
			(end -0.67945 -0.3048)
			(stroke
				(width 0.1)
				(type default)
			)
			(layer "B.Fab")
		)
		(fp_line
			(start -0.67945 0.3048)
			(end -0.120396 0.3048)
			(stroke
				(width 0.1)
				(type default)
			)
			(layer "B.Fab")
		)
		(fp_line
			(start -0.67945 -0.3048)
			(end -0.67945 0.3048)
			(stroke
				(width 0.1)
				(type default)
			)
			(layer "B.Fab")
		)
		(pad "1" smd circle
			(at 0.40005 0)
			(size 0 0)
			(layers "B.Cu" "B.Mask" "B.Paste")
			(net "P2V5_AUX")
		)
		(pad "2" smd circle
			(at -0.40005 0)
			(size 0 0)
			(layers "B.Cu" "B.Mask" "B.Paste")
			(net "GND")
		)
	)
)
